# T6G (Grand Teton) — schematic netlist excerpt (pin names and nets, part order shuffled) for the footprints in the layout excerpt that follows; sources: Cadence DE-HDL packaged netlist, KiCad conversion of 04192023_DAF0TMB3IC0_F0TG_MB_C_brd_V02_OCP.brd

PR109  Q_RES  5.6 1% CHIP  pkg 0402LF  page 206 : A = SW_PVDDIO_P0_BOOT4 ; B = SW_PVDDIO_P0_BOOT4_R
PC568_C0P0_5  Q_CAP  2.2UF 10V 10% X6S  pkg C0402  page 196 : A = PVDDCR_CPU0_P0_PVCC ; B = GND

(kicad_pcb
	(version 20260206)
	(generator "pcbnew")
	(generator_version "10.0")
	(general
		(thickness 1.6)
		(legacy_teardrops no)
	)
	(paper "A4")
	(title_block
		(title "04192023_DAF0TMB3IC0_F0TG_MB_C_brd_V02_OCP.brd")
		(comment 1 "Grand Teton / footprints 4111-4112 of 8354")
	)
	(layers
		(0 "F.Cu" signal "TOP")
		(4 "In1.Cu" signal "GND")
		(6 "In2.Cu" signal "IN1")
		(8 "In3.Cu" signal "GND1")
		(10 "In4.Cu" signal "IN2")
		(12 "In5.Cu" signal "GND2")
		(14 "In6.Cu" signal "IN3")
		(16 "In7.Cu" signal "GND3")
		(18 "In8.Cu" signal "VCC")
		(20 "In9.Cu" signal "VCC1")
		(22 "In10.Cu" signal "GND4")
		(24 "In11.Cu" signal "IN4")
		(26 "In12.Cu" signal "GND5")
		(28 "In13.Cu" signal "IN5")
		(30 "In14.Cu" signal "GND6")
		(32 "In15.Cu" signal "IN6")
		(34 "In16.Cu" signal "GND7")
		(2 "B.Cu" signal "BOTTOM")
		(9 "F.Adhes" user "F.Adhesive")
		(11 "B.Adhes" user "B.Adhesive")
		(13 "F.Paste" user "Package Geometry/Pastemask Top")
		(15 "B.Paste" user "Package Geometry/Pastemask Bottom")
		(5 "F.SilkS" user "Ref Des/Silkscreen Top")
		(7 "B.SilkS" user "Ref Des/Silkscreen Bottom")
		(1 "F.Mask" user "Board Geometry/Soldermask Top")
		(3 "B.Mask" user "Board Geometry/Soldermask Bottom")
		(17 "Dwgs.User" user "User.Drawings")
		(19 "Cmts.User" user "User.Comments")
		(21 "Eco1.User" user "User.Eco1")
		(23 "Eco2.User" user "User.Eco2")
		(25 "Edge.Cuts" user "Board Geometry/Outline")
		(27 "Margin" user)
		(31 "F.CrtYd" user "Package Geometry/Place Bound Top")
		(29 "B.CrtYd" user "Package Geometry/Place Bound Bottom")
		(35 "F.Fab" user "Ref Des/Assembly Top")
		(33 "B.Fab" user "Ref Des/Assembly Bottom")
	)
	(footprint ""
		(layer "F.Cu")
		(at 276.181312 -351.368106 90)
		(property "Reference" "PR109"
			(at 0 0 90)
			(layer "F.SilkS")
			(hide yes)
			(effects
				(font
					(size 1.27 1.27)
				)
			)
		)
		(property "Value" ""
			(at 0 0 90)
			(layer "F.Fab")
			(effects
				(font
					(size 1.27 1.27)
				)
			)
		)
		(duplicate_pad_numbers_are_jumpers no)
		(fp_line
			(start 0.7874 -0.4064)
			(end 0.7874 0.4064)
			(stroke
				(width 0.1524)
				(type default)
			)
			(layer "F.SilkS")
		)
		(fp_line
			(start -0.7874 -0.4064)
			(end 0.7874 -0.4064)
			(stroke
				(width 0.1524)
				(type default)
			)
			(layer "F.SilkS")
		)
		(fp_line
			(start 0.7874 0.4064)
			(end -0.7874 0.4064)
			(stroke
				(width 0.1524)
				(type default)
			)
			(layer "F.SilkS")
		)
		(fp_line
			(start -0.7874 0.4064)
			(end -0.7874 -0.4064)
			(stroke
				(width 0.1524)
				(type default)
			)
			(layer "F.SilkS")
		)
		(fp_line
			(start -0.12065 -0.305054)
			(end -0.12065 -0.2794)
			(stroke
				(width 0.1)
				(type default)
			)
			(layer "F.Fab")
		)
		(fp_line
			(start -0.67945 -0.305054)
			(end -0.12065 -0.305054)
			(stroke
				(width 0.1)
				(type default)
			)
			(layer "F.Fab")
		)
		(fp_line
			(start 0.67945 -0.3048)
			(end 0.67945 0.3048)
			(stroke
				(width 0.1)
				(type default)
			)
			(layer "F.Fab")
		)
		(fp_line
			(start 0.12065 -0.3048)
			(end 0.67945 -0.3048)
			(stroke
				(width 0.1)
				(type default)
			)
			(layer "F.Fab")
		)
		(fp_line
			(start 0.12065 -0.2794)
			(end 0.12065 -0.3048)
			(stroke
				(width 0.1)
				(type default)
			)
			(layer "F.Fab")
		)
		(fp_line
			(start -0.12065 -0.2794)
			(end 0.12065 -0.2794)
			(stroke
				(width 0.1)
				(type default)
			)
			(layer "F.Fab")
		)
		(fp_line
			(start 0.120396 0.2794)
			(end -0.12065 0.2794)
			(stroke
				(width 0.1)
				(type default)
			)
			(layer "F.Fab")
		)
		(fp_line
			(start -0.12065 0.2794)
			(end -0.12065 0.3048)
			(stroke
				(width 0.1)
				(type default)
			)
			(layer "F.Fab")
		)
		(fp_line
			(start 0.67945 0.3048)
			(end 0.120396 0.3048)
			(stroke
				(width 0.1)
				(type default)
			)
			(layer "F.Fab")
		)
		(fp_line
			(start 0.120396 0.3048)
			(end 0.120396 0.2794)
			(stroke
				(width 0.1)
				(type default)
			)
			(layer "F.Fab")
		)
		(fp_line
			(start -0.12065 0.3048)
			(end -0.67945 0.3048)
			(stroke
				(width 0.1)
				(type default)
			)
			(layer "F.Fab")
		)
		(fp_line
			(start -0.67945 0.3048)
			(end -0.67945 -0.305054)
			(stroke
				(width 0.1)
				(type default)
			)
			(layer "F.Fab")
		)
		(pad "1" smd circle
			(at -0.40005 0 90)
			(size 0 0)
			(layers "F.Cu" "F.Mask" "F.Paste")
			(net "SW_PVDDIO_P0_BOOT4")
		)
		(pad "2" smd circle
			(at 0.40005 0 90)
			(size 0 0)
			(layers "F.Cu" "F.Mask" "F.Paste")
			(net "SW_PVDDIO_P0_BOOT4_R")
		)
	)
	(footprint ""
		(layer "F.Cu")
		(at 359.716578 -169.497756 90)
		(property "Reference" "PC568_C0P0_5"
			(at 0 0 90)
			(layer "F.SilkS")
			(hide yes)
			(effects
				(font
					(size 1.27 1.27)
				)
			)
		)
		(property "Value" ""
			(at 0 0 90)
			(layer "F.Fab")
			(effects
				(font
					(size 1.27 1.27)
				)
			)
		)
		(duplicate_pad_numbers_are_jumpers no)
		(fp_line
			(start 0.7874 -0.4064)
			(end 0.7874 0.4064)
			(stroke
				(width 0.1524)
				(type default)
			)
			(layer "F.SilkS")
		)
		(fp_line
			(start -0.7874 -0.4064)
			(end 0.7874 -0.4064)
			(stroke
				(width 0.1524)
				(type default)
			)
			(layer "F.SilkS")
		)
		(fp_line
			(start 0.7874 0.4064)
			(end -0.7874 0.4064)
			(stroke
				(width 0.1524)
				(type default)
			)
			(layer "F.SilkS")
		)
		(fp_line
			(start -0.7874 0.4064)
			(end -0.7874 -0.4064)
			(stroke
				(width 0.1524)
				(type default)
			)
			(layer "F.SilkS")
		)
		(fp_line
			(start -0.12065 -0.305054)
			(end -0.12065 -0.2794)
			(stroke
				(width 0.1)
				(type default)
			)
			(layer "F.Fab")
		)
		(fp_line
			(start -0.67945 -0.305054)
			(end -0.12065 -0.305054)
			(stroke
				(width 0.1)
				(type default)
			)
			(layer "F.Fab")
		)
		(fp_line
			(start 0.67945 -0.3048)
			(end 0.67945 0.3048)
			(stroke
				(width 0.1)
				(type default)
			)
			(layer "F.Fab")
		)
		(fp_line
			(start 0.12065 -0.3048)
			(end 0.67945 -0.3048)
			(stroke
				(width 0.1)
				(type default)
			)
			(layer "F.Fab")
		)
		(fp_line
			(start 0.12065 -0.2794)
			(end 0.12065 -0.3048)
			(stroke
				(width 0.1)
				(type default)
			)
			(layer "F.Fab")
		)
		(fp_line
			(start -0.12065 -0.2794)
			(end 0.12065 -0.2794)
			(stroke
				(width 0.1)
				(type default)
			)
			(layer "F.Fab")
		)
		(fp_line
			(start 0.120396 0.2794)
			(end -0.12065 0.2794)
			(stroke
				(width 0.1)
				(type default)
			)
			(layer "F.Fab")
		)
		(fp_line
			(start -0.12065 0.2794)
			(end -0.12065 0.3048)
			(stroke
				(width 0.1)
				(type default)
			)
			(layer "F.Fab")
		)
		(fp_line
			(start 0.67945 0.3048)
			(end 0.120396 0.3048)
			(stroke
				(width 0.1)
				(type default)
			)
			(layer "F.Fab")
		)
		(fp_line
			(start 0.120396 0.3048)
			(end 0.120396 0.2794)
			(stroke
				(width 0.1)
				(type default)
			)
			(layer "F.Fab")
		)
		(fp_line
			(start -0.12065 0.3048)
			(end -0.67945 0.3048)
			(stroke
				(width 0.1)
				(type default)
			)
			(layer "F.Fab")
		)
		(fp_line
			(start -0.67945 0.3048)
			(end -0.67945 -0.305054)
			(stroke
				(width 0.1)
				(type default)
			)
			(layer "F.Fab")
		)
		(pad "1" smd circle
			(at -0.40005 0 90)
			(size 0 0)
			(layers "F.Cu" "F.Mask" "F.Paste")
			(net "PVDDCR_CPU0_P0_PVCC")
		)
		(pad "2" smd circle
			(at 0.40005 0 90)
			(size 0 0)
			(layers "F.Cu" "F.Mask" "F.Paste")
			(net "GND")
		)
	)
)
